# T6G (Grand Teton) — schematic netlist excerpt (pin names and nets, part order shuffled) for the footprints in the layout excerpt that follows; sources: Cadence DE-HDL packaged netlist, KiCad conversion of 04192023_DAF0TMB3IC0_F0TG_MB_C_brd_V02_OCP.brd

C2601  Q_CAP  22UF 4V 20% X6S  pkg C0402  page 70 : A = PVDD11_S3_P0 ; B = GND
L21  Q_INDUCTOR  100NH/16A IND  pkg SMLF  page 301 : \1\ = P0V9_CPU0_RT_2D ; \2\ = P0V9_CPU0_RT2_2A
R8031  Q_RES  0 5% CHIP  pkg 0402LF  page 152 : A = P12V_SCM_FLTB_N ; B = P12V_SCM_FAULT_R_N

(kicad_pcb
	(version 20260206)
	(generator "pcbnew")
	(generator_version "10.0")
	(general
		(thickness 1.6)
		(legacy_teardrops no)
	)
	(paper "A4")
	(title_block
		(title "04192023_DAF0TMB3IC0_F0TG_MB_C_brd_V02_OCP.brd")
		(comment 1 "Grand Teton / footprints 3877-3879 of 8354")
	)
	(layers
		(0 "F.Cu" signal "TOP")
		(4 "In1.Cu" signal "GND")
		(6 "In2.Cu" signal "IN1")
		(8 "In3.Cu" signal "GND1")
		(10 "In4.Cu" signal "IN2")
		(12 "In5.Cu" signal "GND2")
		(14 "In6.Cu" signal "IN3")
		(16 "In7.Cu" signal "GND3")
		(18 "In8.Cu" signal "VCC")
		(20 "In9.Cu" signal "VCC1")
		(22 "In10.Cu" signal "GND4")
		(24 "In11.Cu" signal "IN4")
		(26 "In12.Cu" signal "GND5")
		(28 "In13.Cu" signal "IN5")
		(30 "In14.Cu" signal "GND6")
		(32 "In15.Cu" signal "IN6")
		(34 "In16.Cu" signal "GND7")
		(2 "B.Cu" signal "BOTTOM")
		(9 "F.Adhes" user "F.Adhesive")
		(11 "B.Adhes" user "B.Adhesive")
		(13 "F.Paste" user "Package Geometry/Pastemask Top")
		(15 "B.Paste" user "Package Geometry/Pastemask Bottom")
		(5 "F.SilkS" user "Ref Des/Silkscreen Top")
		(7 "B.SilkS" user "Ref Des/Silkscreen Bottom")
		(1 "F.Mask" user "Board Geometry/Soldermask Top")
		(3 "B.Mask" user "Board Geometry/Soldermask Bottom")
		(17 "Dwgs.User" user "User.Drawings")
		(19 "Cmts.User" user "User.Comments")
		(21 "Eco1.User" user "User.Eco1")
		(23 "Eco2.User" user "User.Eco2")
		(25 "Edge.Cuts" user "Board Geometry/Outline")
		(27 "Margin" user)
		(31 "F.CrtYd" user "Package Geometry/Place Bound Top")
		(29 "B.CrtYd" user "Package Geometry/Place Bound Bottom")
		(35 "F.Fab" user "Ref Des/Assembly Top")
		(33 "B.Fab" user "Ref Des/Assembly Bottom")
	)
	(footprint ""
		(layer "F.Cu")
		(at 357.517192 -261.747762 -90)
		(property "Reference" "C2601"
			(at 0 0 270)
			(layer "F.SilkS")
			(hide yes)
			(effects
				(font
					(size 1.27 1.27)
				)
			)
		)
		(property "Value" ""
			(at 0 0 270)
			(layer "F.Fab")
			(effects
				(font
					(size 1.27 1.27)
				)
			)
		)
		(duplicate_pad_numbers_are_jumpers no)
		(fp_line
			(start -0.7874 0.4064)
			(end -0.7874 -0.4064)
			(stroke
				(width 0.1524)
				(type default)
			)
			(layer "F.SilkS")
		)
		(fp_line
			(start 0.7874 0.4064)
			(end -0.7874 0.4064)
			(stroke
				(width 0.1524)
				(type default)
			)
			(layer "F.SilkS")
		)
		(fp_line
			(start -0.7874 -0.4064)
			(end 0.7874 -0.4064)
			(stroke
				(width 0.1524)
				(type default)
			)
			(layer "F.SilkS")
		)
		(fp_line
			(start 0.7874 -0.4064)
			(end 0.7874 0.4064)
			(stroke
				(width 0.1524)
				(type default)
			)
			(layer "F.SilkS")
		)
		(fp_line
			(start -0.67945 0.3048)
			(end -0.67945 -0.305054)
			(stroke
				(width 0.1)
				(type default)
			)
			(layer "F.Fab")
		)
		(fp_line
			(start -0.12065 0.3048)
			(end -0.67945 0.3048)
			(stroke
				(width 0.1)
				(type default)
			)
			(layer "F.Fab")
		)
		(fp_line
			(start 0.120396 0.3048)
			(end 0.120396 0.2794)
			(stroke
				(width 0.1)
				(type default)
			)
			(layer "F.Fab")
		)
		(fp_line
			(start 0.67945 0.3048)
			(end 0.120396 0.3048)
			(stroke
				(width 0.1)
				(type default)
			)
			(layer "F.Fab")
		)
		(fp_line
			(start -0.12065 0.2794)
			(end -0.12065 0.3048)
			(stroke
				(width 0.1)
				(type default)
			)
			(layer "F.Fab")
		)
		(fp_line
			(start 0.120396 0.2794)
			(end -0.12065 0.2794)
			(stroke
				(width 0.1)
				(type default)
			)
			(layer "F.Fab")
		)
		(fp_line
			(start -0.12065 -0.2794)
			(end 0.12065 -0.2794)
			(stroke
				(width 0.1)
				(type default)
			)
			(layer "F.Fab")
		)
		(fp_line
			(start 0.12065 -0.2794)
			(end 0.12065 -0.3048)
			(stroke
				(width 0.1)
				(type default)
			)
			(layer "F.Fab")
		)
		(fp_line
			(start 0.12065 -0.3048)
			(end 0.67945 -0.3048)
			(stroke
				(width 0.1)
				(type default)
			)
			(layer "F.Fab")
		)
		(fp_line
			(start 0.67945 -0.3048)
			(end 0.67945 0.3048)
			(stroke
				(width 0.1)
				(type default)
			)
			(layer "F.Fab")
		)
		(fp_line
			(start -0.67945 -0.305054)
			(end -0.12065 -0.305054)
			(stroke
				(width 0.1)
				(type default)
			)
			(layer "F.Fab")
		)
		(fp_line
			(start -0.12065 -0.305054)
			(end -0.12065 -0.2794)
			(stroke
				(width 0.1)
				(type default)
			)
			(layer "F.Fab")
		)
		(pad "1" smd circle
			(at -0.40005 0 270)
			(size 0 0)
			(layers "F.Cu" "F.Mask" "F.Paste")
			(net "PVDD11_S3_P0")
		)
		(pad "2" smd circle
			(at 0.40005 0 270)
			(size 0 0)
			(layers "F.Cu" "F.Mask" "F.Paste")
			(net "GND")
		)
	)
	(footprint ""
		(layer "F.Cu")
		(at 189.357 -51.054 90)
		(property "Reference" "R8031"
			(at 0 0 90)
			(layer "F.SilkS")
			(hide yes)
			(effects
				(font
					(size 1.27 1.27)
				)
			)
		)
		(property "Value" ""
			(at 0 0 90)
			(layer "F.Fab")
			(effects
				(font
					(size 1.27 1.27)
				)
			)
		)
		(duplicate_pad_numbers_are_jumpers no)
		(fp_line
			(start 0.7874 -0.4064)
			(end 0.7874 0.4064)
			(stroke
				(width 0.1524)
				(type default)
			)
			(layer "F.SilkS")
		)
		(fp_line
			(start -0.7874 -0.4064)
			(end 0.7874 -0.4064)
			(stroke
				(width 0.1524)
				(type default)
			)
			(layer "F.SilkS")
		)
		(fp_line
			(start 0.7874 0.4064)
			(end -0.7874 0.4064)
			(stroke
				(width 0.1524)
				(type default)
			)
			(layer "F.SilkS")
		)
		(fp_line
			(start -0.7874 0.4064)
			(end -0.7874 -0.4064)
			(stroke
				(width 0.1524)
				(type default)
			)
			(layer "F.SilkS")
		)
		(fp_line
			(start -0.12065 -0.305054)
			(end -0.12065 -0.2794)
			(stroke
				(width 0.1)
				(type default)
			)
			(layer "F.Fab")
		)
		(fp_line
			(start -0.67945 -0.305054)
			(end -0.12065 -0.305054)
			(stroke
				(width 0.1)
				(type default)
			)
			(layer "F.Fab")
		)
		(fp_line
			(start 0.67945 -0.3048)
			(end 0.67945 0.3048)
			(stroke
				(width 0.1)
				(type default)
			)
			(layer "F.Fab")
		)
		(fp_line
			(start 0.12065 -0.3048)
			(end 0.67945 -0.3048)
			(stroke
				(width 0.1)
				(type default)
			)
			(layer "F.Fab")
		)
		(fp_line
			(start 0.12065 -0.2794)
			(end 0.12065 -0.3048)
			(stroke
				(width 0.1)
				(type default)
			)
			(layer "F.Fab")
		)
		(fp_line
			(start -0.12065 -0.2794)
			(end 0.12065 -0.2794)
			(stroke
				(width 0.1)
				(type default)
			)
			(layer "F.Fab")
		)
		(fp_line
			(start 0.120396 0.2794)
			(end -0.12065 0.2794)
			(stroke
				(width 0.1)
				(type default)
			)
			(layer "F.Fab")
		)
		(fp_line
			(start -0.12065 0.2794)
			(end -0.12065 0.3048)
			(stroke
				(width 0.1)
				(type default)
			)
			(layer "F.Fab")
		)
		(fp_line
			(start 0.67945 0.3048)
			(end 0.120396 0.3048)
			(stroke
				(width 0.1)
				(type default)
			)
			(layer "F.Fab")
		)
		(fp_line
			(start 0.120396 0.3048)
			(end 0.120396 0.2794)
			(stroke
				(width 0.1)
				(type default)
			)
			(layer "F.Fab")
		)
		(fp_line
			(start -0.12065 0.3048)
			(end -0.67945 0.3048)
			(stroke
				(width 0.1)
				(type default)
			)
			(layer "F.Fab")
		)
		(fp_line
			(start -0.67945 0.3048)
			(end -0.67945 -0.305054)
			(stroke
				(width 0.1)
				(type default)
			)
			(layer "F.Fab")
		)
		(pad "1" smd circle
			(at -0.40005 0 90)
			(size 0 0)
			(layers "F.Cu" "F.Mask" "F.Paste")
			(net "P12V_SCM_FLTB_N")
		)
		(pad "2" smd circle
			(at 0.40005 0 90)
			(size 0 0)
			(layers "F.Cu" "F.Mask" "F.Paste")
			(net "P12V_SCM_FAULT_R_N")
		)
	)
	(footprint ""
		(layer "F.Cu")
		(at 396.250668 -400.903694)
		(property "Reference" "L21"
			(at -3.06197 -1.343914 90)
			(unlocked yes)
			(layer "F.SilkS")
			(effects
				(font
					(size 0.7874 0.5842)
					(thickness 0.1524)
				)
				(justify left)
			)
		)
		(property "Value" ""
			(at 0 0 0)
			(layer "F.Fab")
			(effects
				(font
					(size 1.27 1.27)
				)
			)
		)
		(duplicate_pad_numbers_are_jumpers no)
		(fp_line
			(start -2.249932 -2.249932)
			(end 2.249932 -2.249932)
			(stroke
				(width 0.1524)
				(type default)
			)
			(layer "F.SilkS")
		)
		(fp_line
			(start -2.249932 -1.3843)
			(end -2.249932 -2.249932)
			(stroke
				(width 0.1524)
				(type default)
			)
			(layer "F.SilkS")
		)
		(fp_line
			(start -2.249932 2.249932)
			(end -2.249932 1.3843)
			(stroke
				(width 0.1524)
				(type default)
			)
			(layer "F.SilkS")
		)
		(fp_line
			(start 2.249932 -2.249932)
			(end 2.249932 -1.3843)
			(stroke
				(width 0.1524)
				(type default)
			)
			(layer "F.SilkS")
		)
		(fp_line
			(start 2.249932 1.3843)
			(end 2.249932 2.249932)
			(stroke
				(width 0.1524)
				(type default)
			)
			(layer "F.SilkS")
		)
		(fp_line
			(start 2.249932 2.249932)
			(end -2.249932 2.249932)
			(stroke
				(width 0.1524)
				(type default)
			)
			(layer "F.SilkS")
		)
		(fp_line
			(start -2.249932 -2.249932)
			(end 2.249932 -2.249932)
			(stroke
				(width 0.1)
				(type default)
			)
			(layer "F.Fab")
		)
		(fp_line
			(start -2.249932 2.249932)
			(end -2.249932 -2.249932)
			(stroke
				(width 0.1)
				(type default)
			)
			(layer "F.Fab")
		)
		(fp_line
			(start 2.249932 -2.249932)
			(end 2.249932 2.249932)
			(stroke
				(width 0.1)
				(type default)
			)
			(layer "F.Fab")
		)
		(fp_line
			(start 2.249932 2.249932)
			(end -2.249932 2.249932)
			(stroke
				(width 0.1)
				(type default)
			)
			(layer "F.Fab")
		)
		(pad "1" smd rect
			(at -1.82499 0)
			(size 1.0668 2.5146)
			(layers "F.Cu" "F.Mask" "F.Paste")
			(net "P0V9_CPU0_RT_2D")
		)
		(pad "2" smd rect
			(at 1.82499 0)
			(size 1.0668 2.5146)
			(layers "F.Cu" "F.Mask" "F.Paste")
			(net "P0V9_CPU0_RT2_2A")
		)
	)
)
